# SCM (Grand Teton) — schematic netlist excerpt (pin names and nets, part order shuffled) for the footprints in the layout excerpt that follows; sources: Cadence DE-HDL packaged netlist, KiCad conversion of 12092022_DA0F0TMDCD0_F0T_Management_Board_D_brd_V3_OCP.brd

R595  Q_RES  4.7K 1% EMPTY  pkg 0402LF  page 42 : A = P3V3_AUX ; B = BMC_CPLD_GPIO_8
R59  Q_RES  10K 1% CHIP  pkg 0402LF  page 46 : A = P3V3_AUX ; B = IRQ_TPM_SPI_N

(kicad_pcb
	(version 20260206)
	(generator "pcbnew")
	(generator_version "10.0")
	(general
		(thickness 1.6)
		(legacy_teardrops no)
	)
	(paper "A4")
	(title_block
		(title "12092022_DA0F0TMDCD0_F0T_Management_Board_D_brd_V3_OCP.brd")
		(comment 1 "Grand Teton / footprints 665-666 of 1440")
	)
	(layers
		(0 "F.Cu" signal "TOP")
		(4 "In1.Cu" signal "GND")
		(6 "In2.Cu" signal "IN1")
		(8 "In3.Cu" signal "GND1")
		(10 "In4.Cu" signal "IN2")
		(12 "In5.Cu" signal "VCC")
		(14 "In6.Cu" signal "VCC1")
		(16 "In7.Cu" signal "IN3")
		(18 "In8.Cu" signal "GND2")
		(20 "In9.Cu" signal "IN4")
		(22 "In10.Cu" signal "GND3")
		(2 "B.Cu" signal "BOTTOM")
		(9 "F.Adhes" user "F.Adhesive")
		(11 "B.Adhes" user "B.Adhesive")
		(13 "F.Paste" user "Package Geometry/Pastemask Top")
		(15 "B.Paste" user "Package Geometry/Pastemask Bottom")
		(5 "F.SilkS" user "Ref Des/Silkscreen Top")
		(7 "B.SilkS" user "Ref Des/Silkscreen Bottom")
		(1 "F.Mask" user "Board Geometry/Soldermask Top")
		(3 "B.Mask" user "Board Geometry/Soldermask Bottom")
		(17 "Dwgs.User" user "User.Drawings")
		(19 "Cmts.User" user "User.Comments")
		(21 "Eco1.User" user "User.Eco1")
		(23 "Eco2.User" user "User.Eco2")
		(25 "Edge.Cuts" user "Board Geometry/Outline")
		(27 "Margin" user)
		(31 "F.CrtYd" user "Package Geometry/Place Bound Top")
		(29 "B.CrtYd" user "Package Geometry/Place Bound Bottom")
		(35 "F.Fab" user "Ref Des/Assembly Top")
		(33 "B.Fab" user "Ref Des/Assembly Bottom")
	)
	(footprint ""
		(layer "F.Cu")
		(at 12.319 -92.456 180)
		(property "Reference" "R595"
			(at 0 0 180)
			(layer "F.SilkS")
			(hide yes)
			(effects
				(font
					(size 1.27 1.27)
				)
			)
		)
		(property "Value" ""
			(at 0 0 180)
			(layer "F.Fab")
			(effects
				(font
					(size 1.27 1.27)
				)
			)
		)
		(duplicate_pad_numbers_are_jumpers no)
		(fp_line
			(start 0.7874 0.4064)
			(end -0.7874 0.4064)
			(stroke
				(width 0.1524)
				(type default)
			)
			(layer "F.SilkS")
		)
		(fp_line
			(start 0.7874 -0.4064)
			(end 0.7874 0.4064)
			(stroke
				(width 0.1524)
				(type default)
			)
			(layer "F.SilkS")
		)
		(fp_line
			(start -0.7874 0.4064)
			(end -0.7874 -0.4064)
			(stroke
				(width 0.1524)
				(type default)
			)
			(layer "F.SilkS")
		)
		(fp_line
			(start -0.7874 -0.4064)
			(end 0.7874 -0.4064)
			(stroke
				(width 0.1524)
				(type default)
			)
			(layer "F.SilkS")
		)
		(fp_line
			(start 0.67945 0.3048)
			(end 0.120396 0.3048)
			(stroke
				(width 0.1)
				(type default)
			)
			(layer "F.Fab")
		)
		(fp_line
			(start 0.67945 -0.3048)
			(end 0.67945 0.3048)
			(stroke
				(width 0.1)
				(type default)
			)
			(layer "F.Fab")
		)
		(fp_line
			(start 0.12065 -0.2794)
			(end 0.12065 -0.3048)
			(stroke
				(width 0.1)
				(type default)
			)
			(layer "F.Fab")
		)
		(fp_line
			(start 0.12065 -0.3048)
			(end 0.67945 -0.3048)
			(stroke
				(width 0.1)
				(type default)
			)
			(layer "F.Fab")
		)
		(fp_line
			(start 0.120396 0.3048)
			(end 0.120396 0.2794)
			(stroke
				(width 0.1)
				(type default)
			)
			(layer "F.Fab")
		)
		(fp_line
			(start 0.120396 0.2794)
			(end -0.12065 0.2794)
			(stroke
				(width 0.1)
				(type default)
			)
			(layer "F.Fab")
		)
		(fp_line
			(start -0.12065 0.3048)
			(end -0.67945 0.3048)
			(stroke
				(width 0.1)
				(type default)
			)
			(layer "F.Fab")
		)
		(fp_line
			(start -0.12065 0.2794)
			(end -0.12065 0.3048)
			(stroke
				(width 0.1)
				(type default)
			)
			(layer "F.Fab")
		)
		(fp_line
			(start -0.12065 -0.2794)
			(end 0.12065 -0.2794)
			(stroke
				(width 0.1)
				(type default)
			)
			(layer "F.Fab")
		)
		(fp_line
			(start -0.12065 -0.305054)
			(end -0.12065 -0.2794)
			(stroke
				(width 0.1)
				(type default)
			)
			(layer "F.Fab")
		)
		(fp_line
			(start -0.67945 0.3048)
			(end -0.67945 -0.305054)
			(stroke
				(width 0.1)
				(type default)
			)
			(layer "F.Fab")
		)
		(fp_line
			(start -0.67945 -0.305054)
			(end -0.12065 -0.305054)
			(stroke
				(width 0.1)
				(type default)
			)
			(layer "F.Fab")
		)
		(pad "1" smd circle
			(at -0.40005 0 180)
			(size 0 0)
			(layers "F.Cu" "F.Mask" "F.Paste")
			(net "P3V3_AUX")
		)
		(pad "2" smd circle
			(at 0.40005 0 180)
			(size 0 0)
			(layers "F.Cu" "F.Mask" "F.Paste")
			(net "BMC_CPLD_GPIO_8")
		)
	)
	(footprint ""
		(layer "F.Cu")
		(at 72.25665 -94.871032 -90)
		(property "Reference" "R59"
			(at 0 0 270)
			(layer "F.SilkS")
			(hide yes)
			(effects
				(font
					(size 1.27 1.27)
				)
			)
		)
		(property "Value" ""
			(at 0 0 270)
			(layer "F.Fab")
			(effects
				(font
					(size 1.27 1.27)
				)
			)
		)
		(duplicate_pad_numbers_are_jumpers no)
		(fp_line
			(start -0.7874 0.4064)
			(end -0.7874 -0.4064)
			(stroke
				(width 0.1524)
				(type default)
			)
			(layer "F.SilkS")
		)
		(fp_line
			(start 0.7874 0.4064)
			(end -0.7874 0.4064)
			(stroke
				(width 0.1524)
				(type default)
			)
			(layer "F.SilkS")
		)
		(fp_line
			(start -0.7874 -0.4064)
			(end 0.7874 -0.4064)
			(stroke
				(width 0.1524)
				(type default)
			)
			(layer "F.SilkS")
		)
		(fp_line
			(start 0.7874 -0.4064)
			(end 0.7874 0.4064)
			(stroke
				(width 0.1524)
				(type default)
			)
			(layer "F.SilkS")
		)
		(fp_line
			(start -0.67945 0.3048)
			(end -0.67945 -0.305054)
			(stroke
				(width 0.1)
				(type default)
			)
			(layer "F.Fab")
		)
		(fp_line
			(start -0.12065 0.3048)
			(end -0.67945 0.3048)
			(stroke
				(width 0.1)
				(type default)
			)
			(layer "F.Fab")
		)
		(fp_line
			(start 0.120396 0.3048)
			(end 0.120396 0.2794)
			(stroke
				(width 0.1)
				(type default)
			)
			(layer "F.Fab")
		)
		(fp_line
			(start 0.67945 0.3048)
			(end 0.120396 0.3048)
			(stroke
				(width 0.1)
				(type default)
			)
			(layer "F.Fab")
		)
		(fp_line
			(start -0.12065 0.2794)
			(end -0.12065 0.3048)
			(stroke
				(width 0.1)
				(type default)
			)
			(layer "F.Fab")
		)
		(fp_line
			(start 0.120396 0.2794)
			(end -0.12065 0.2794)
			(stroke
				(width 0.1)
				(type default)
			)
			(layer "F.Fab")
		)
		(fp_line
			(start -0.12065 -0.2794)
			(end 0.12065 -0.2794)
			(stroke
				(width 0.1)
				(type default)
			)
			(layer "F.Fab")
		)
		(fp_line
			(start 0.12065 -0.2794)
			(end 0.12065 -0.3048)
			(stroke
				(width 0.1)
				(type default)
			)
			(layer "F.Fab")
		)
		(fp_line
			(start 0.12065 -0.3048)
			(end 0.67945 -0.3048)
			(stroke
				(width 0.1)
				(type default)
			)
			(layer "F.Fab")
		)
		(fp_line
			(start 0.67945 -0.3048)
			(end 0.67945 0.3048)
			(stroke
				(width 0.1)
				(type default)
			)
			(layer "F.Fab")
		)
		(fp_line
			(start -0.67945 -0.305054)
			(end -0.12065 -0.305054)
			(stroke
				(width 0.1)
				(type default)
			)
			(layer "F.Fab")
		)
		(fp_line
			(start -0.12065 -0.305054)
			(end -0.12065 -0.2794)
			(stroke
				(width 0.1)
				(type default)
			)
			(layer "F.Fab")
		)
		(pad "1" smd circle
			(at -0.40005 0 270)
			(size 0 0)
			(layers "F.Cu" "F.Mask" "F.Paste")
			(net "P3V3_AUX")
		)
		(pad "2" smd circle
			(at 0.40005 0 270)
			(size 0 0)
			(layers "F.Cu" "F.Mask" "F.Paste")
			(net "IRQ_TPM_SPI_N")
		)
	)
)
